(kicad_pcb
	(version 20260206)
	(generator "pcbnew")
	(generator_version "10.0")
	(general
		(thickness 1.6)
		(legacy_teardrops no)
	)
	(paper "A4")
	(title_block
		(title "04192023_DAF0TMB3IC0_F0TG_MB_C_brd_V02_OCP.brd")
		(comment 1 "Grand Teton / footprints 580-582 of 8354")
	)
	(layers
		(0 "F.Cu" signal "TOP")
		(4 "In1.Cu" signal "GND")
		(6 "In2.Cu" signal "IN1")
		(8 "In3.Cu" signal "GND1")
		(10 "In4.Cu" signal "IN2")
		(12 "In5.Cu" signal "GND2")
		(14 "In6.Cu" signal "IN3")
		(16 "In7.Cu" signal "GND3")
		(18 "In8.Cu" signal "VCC")
		(20 "In9.Cu" signal "VCC1")
		(22 "In10.Cu" signal "GND4")
		(24 "In11.Cu" signal "IN4")
		(26 "In12.Cu" signal "GND5")
		(28 "In13.Cu" signal "IN5")
		(30 "In14.Cu" signal "GND6")
		(32 "In15.Cu" signal "IN6")
		(34 "In16.Cu" signal "GND7")
		(2 "B.Cu" signal "BOTTOM")
		(9 "F.Adhes" user "F.Adhesive")
		(11 "B.Adhes" user "B.Adhesive")
		(13 "F.Paste" user "Package Geometry/Pastemask Top")
		(15 "B.Paste" user "Package Geometry/Pastemask Bottom")
		(5 "F.SilkS" user "Ref Des/Silkscreen Top")
		(7 "B.SilkS" user "Ref Des/Silkscreen Bottom")
		(1 "F.Mask" user "Board Geometry/Soldermask Top")
		(3 "B.Mask" user "Board Geometry/Soldermask Bottom")
		(17 "Dwgs.User" user "User.Drawings")
		(19 "Cmts.User" user "User.Comments")
		(21 "Eco1.User" user "User.Eco1")
		(23 "Eco2.User" user "User.Eco2")
		(25 "Edge.Cuts" user "Board Geometry/Outline")
		(27 "Margin" user)
		(31 "F.CrtYd" user "Package Geometry/Place Bound Top")
		(29 "B.CrtYd" user "Package Geometry/Place Bound Bottom")
		(35 "F.Fab" user "Ref Des/Assembly Top")
		(33 "B.Fab" user "Ref Des/Assembly Bottom")
	)
	(footprint ""
		(layer "F.Cu")
		(at 175.895 -129.377948 90)
		(property "Reference" "R249"
			(at 0 0 90)
			(layer "F.SilkS")
			(hide yes)
			(effects
				(font
					(size 1.27 1.27)
				)
			)
		)
		(property "Value" ""
			(at 0 0 90)
			(layer "F.Fab")
			(effects
				(font
					(size 1.27 1.27)
				)
			)
		)
		(duplicate_pad_numbers_are_jumpers no)
		(fp_line
			(start 0.7874 -0.4064)
			(end 0.7874 0.4064)
			(stroke
				(width 0.1524)
				(type default)
			)
			(layer "F.SilkS")
		)
		(fp_line
			(start -0.7874 -0.4064)
			(end 0.7874 -0.4064)
			(stroke
				(width 0.1524)
				(type default)
			)
			(layer "F.SilkS")
		)
		(fp_line
			(start 0.7874 0.4064)
			(end -0.7874 0.4064)
			(stroke
				(width 0.1524)
				(type default)
			)
			(layer "F.SilkS")
		)
		(fp_line
			(start -0.7874 0.4064)
			(end -0.7874 -0.4064)
			(stroke
				(width 0.1524)
				(type default)
			)
			(layer "F.SilkS")
		)
		(fp_line
			(start -0.12065 -0.305054)
			(end -0.12065 -0.2794)
			(stroke
				(width 0.1)
				(type default)
			)
			(layer "F.Fab")
		)
		(fp_line
			(start -0.67945 -0.305054)
			(end -0.12065 -0.305054)
			(stroke
				(width 0.1)
				(type default)
			)
			(layer "F.Fab")
		)
		(fp_line
			(start 0.67945 -0.3048)
			(end 0.67945 0.3048)
			(stroke
				(width 0.1)
				(type default)
			)
			(layer "F.Fab")
		)
		(fp_line
			(start 0.12065 -0.3048)
			(end 0.67945 -0.3048)
			(stroke
				(width 0.1)
				(type default)
			)
			(layer "F.Fab")
		)
		(fp_line
			(start 0.12065 -0.2794)
			(end 0.12065 -0.3048)
			(stroke
				(width 0.1)
				(type default)
			)
			(layer "F.Fab")
		)
		(fp_line
			(start -0.12065 -0.2794)
			(end 0.12065 -0.2794)
			(stroke
				(width 0.1)
				(type default)
			)
			(layer "F.Fab")
		)
		(fp_line
			(start 0.120396 0.2794)
			(end -0.12065 0.2794)
			(stroke
				(width 0.1)
				(type default)
			)
			(layer "F.Fab")
		)
		(fp_line
			(start -0.12065 0.2794)
			(end -0.12065 0.3048)
			(stroke
				(width 0.1)
				(type default)
			)
			(layer "F.Fab")
		)
		(fp_line
			(start 0.67945 0.3048)
			(end 0.120396 0.3048)
			(stroke
				(width 0.1)
				(type default)
			)
			(layer "F.Fab")
		)
		(fp_line
			(start 0.120396 0.3048)
			(end 0.120396 0.2794)
			(stroke
				(width 0.1)
				(type default)
			)
			(layer "F.Fab")
		)
		(fp_line
			(start -0.12065 0.3048)
			(end -0.67945 0.3048)
			(stroke
				(width 0.1)
				(type default)
			)
			(layer "F.Fab")
		)
		(fp_line
			(start -0.67945 0.3048)
			(end -0.67945 -0.305054)
			(stroke
				(width 0.1)
				(type default)
			)
			(layer "F.Fab")
		)
		(pad "1" smd circle
			(at -0.40005 0 90)
			(size 0 0)
			(layers "F.Cu" "F.Mask" "F.Paste")
			(net "FM_CPU0_SLP_S3_N")
		)
		(pad "2" smd circle
			(at 0.40005 0 90)
			(size 0 0)
			(layers "F.Cu" "F.Mask" "F.Paste")
			(net "CPU0_SLP_S3_N")
		)
	)
	(footprint ""
		(layer "F.Cu")
		(at 363.51845 -22.207728 90)
		(property "Reference" "J13"
			(at -3.17754 -2.820924 90)
			(unlocked yes)
			(layer "F.SilkS")
			(effects
				(font
					(size 0.7874 0.5842)
					(thickness 0.1524)
				)
				(justify left)
			)
		)
		(property "Value" ""
			(at 0 0 90)
			(layer "F.Fab")
			(effects
				(font
					(size 1.27 1.27)
				)
			)
		)
		(duplicate_pad_numbers_are_jumpers no)
		(fp_line
			(start 1.700022 -1.999996)
			(end -2.999994 -1.999996)
			(stroke
				(width 0.1524)
				(type default)
			)
			(layer "F.SilkS")
		)
		(fp_line
			(start -2.999994 -1.999996)
			(end -2.999994 7.999984)
			(stroke
				(width 0.1524)
				(type default)
			)
			(layer "F.SilkS")
		)
		(fp_line
			(start 1.199896 -1.500124)
			(end 1.199896 0.999998)
			(stroke
				(width 0.1524)
				(type default)
			)
			(layer "F.SilkS")
		)
		(fp_line
			(start -2.500122 -1.500124)
			(end 1.199896 -1.500124)
			(stroke
				(width 0.1524)
				(type default)
			)
			(layer "F.SilkS")
		)
		(fp_line
			(start 1.199896 0.999998)
			(end 1.700022 0.999998)
			(stroke
				(width 0.1524)
				(type default)
			)
			(layer "F.SilkS")
		)
		(fp_line
			(start 1.700022 4.99999)
			(end 1.199896 4.99999)
			(stroke
				(width 0.1524)
				(type default)
			)
			(layer "F.SilkS")
		)
		(fp_line
			(start 1.199896 4.99999)
			(end 1.199896 7.500112)
			(stroke
				(width 0.1524)
				(type default)
			)
			(layer "F.SilkS")
		)
		(fp_line
			(start -2.500122 5.425694)
			(end -2.500122 -1.500124)
			(stroke
				(width 0.1524)
				(type default)
			)
			(layer "F.SilkS")
		)
		(fp_line
			(start 1.199896 7.500112)
			(end -2.500122 7.500112)
			(stroke
				(width 0.1524)
				(type default)
			)
			(layer "F.SilkS")
		)
		(fp_line
			(start -2.500122 7.500112)
			(end -2.500122 6.568694)
			(stroke
				(width 0.1524)
				(type default)
			)
			(layer "F.SilkS")
		)
		(fp_line
			(start 1.700022 7.999984)
			(end 1.700022 -1.999996)
			(stroke
				(width 0.1524)
				(type default)
			)
			(layer "F.SilkS")
		)
		(fp_line
			(start -0.899922 7.999984)
			(end 1.700022 7.999984)
			(stroke
				(width 0.1524)
				(type default)
			)
			(layer "F.SilkS")
		)
		(fp_line
			(start -2.999994 7.999984)
			(end -0.899922 7.999984)
			(stroke
				(width 0.1524)
				(type default)
			)
			(layer "F.SilkS")
		)
		(fp_poly
			(pts
				(xy 0.762 -3.731006) (xy 0 -2.207006) (xy -0.762 -3.731006)
			)
			(stroke
				(width 0)
				(type default)
			)
			(fill yes)
			(layer "F.SilkS")
		)
		(fp_line
			(start 1.700022 -1.999996)
			(end -2.999994 -1.999996)
			(stroke
				(width 0.1)
				(type default)
			)
			(layer "F.Fab")
		)
		(fp_line
			(start -2.999994 -1.999996)
			(end -2.999994 7.999984)
			(stroke
				(width 0.1)
				(type default)
			)
			(layer "F.Fab")
		)
		(fp_line
			(start 1.199896 -1.500124)
			(end 1.199896 0.999998)
			(stroke
				(width 0.1)
				(type default)
			)
			(layer "F.Fab")
		)
		(fp_line
			(start -2.500122 -1.500124)
			(end 1.199896 -1.500124)
			(stroke
				(width 0.1)
				(type default)
			)
			(layer "F.Fab")
		)
		(fp_line
			(start 1.199896 0.999998)
			(end 1.700022 0.999998)
			(stroke
				(width 0.1)
				(type default)
			)
			(layer "F.Fab")
		)
		(fp_line
			(start 1.700022 4.99999)
			(end 1.199896 4.99999)
			(stroke
				(width 0.1)
				(type default)
			)
			(layer "F.Fab")
		)
		(fp_line
			(start 1.199896 4.99999)
			(end 1.199896 7.500112)
			(stroke
				(width 0.1)
				(type default)
			)
			(layer "F.Fab")
		)
		(fp_line
			(start -2.500122 6.657594)
			(end -2.500122 -1.500124)
			(stroke
				(width 0.1)
				(type default)
			)
			(layer "F.Fab")
		)
		(fp_line
			(start 1.199896 7.500112)
			(end -2.500122 7.500112)
			(stroke
				(width 0.1)
				(type default)
			)
			(layer "F.Fab")
		)
		(fp_line
			(start -2.500122 7.500112)
			(end -2.500122 6.606794)
			(stroke
				(width 0.1)
				(type default)
			)
			(layer "F.Fab")
		)
		(fp_line
			(start 1.700022 7.999984)
			(end 1.700022 -1.999996)
			(stroke
				(width 0.1)
				(type default)
			)
			(layer "F.Fab")
		)
		(fp_line
			(start -0.899922 7.999984)
			(end 1.700022 7.999984)
			(stroke
				(width 0.1)
				(type default)
			)
			(layer "F.Fab")
		)
		(fp_line
			(start -2.999994 7.999984)
			(end -0.899922 7.999984)
			(stroke
				(width 0.1)
				(type default)
			)
			(layer "F.Fab")
		)
		(fp_poly
			(pts
				(xy 0 -2.207006) (xy -0.762 -3.731006) (xy 0.762 -3.731006)
			)
			(stroke
				(width 0)
				(type default)
			)
			(fill yes)
			(layer "F.Fab")
		)
		(pad "" np_thru_hole circle
			(at -1.800098 5.999988 180)
			(size 1.143 1.143)
			(drill 1.143)
			(layers "*.Cu" "*.Mask")
			(clearance 0.381)
			(thermal_gap 0.381)
		)
		(pad "1" thru_hole rect
			(at 0 0 180)
			(size 1.2192 1.2192)
			(drill 0.8128)
			(layers "*.Cu" "*.Mask")
			(remove_unused_layers no)
			(net "UART_VCC_J13")
			(clearance 0.0508)
			(thermal_gap 0.0508)
			(padstack
				(mode front_inner_back)
				(layer "Inner"
					(shape circle)
					(size 1.2192 1.2192)
					(clearance 0.0508)
				)
				(layer "B.Cu"
					(shape rect)
					(size 1.2192 1.2192)
					(clearance 0.0508)
				)
			)
		)
		(pad "2" thru_hole circle
			(at 0 1.999996 180)
			(size 1.2192 1.2192)
			(drill 0.8128)
			(layers "*.Cu" "*.Mask")
			(remove_unused_layers no)
			(net "UART_CPU0_LVC3_UART0_RX")
			(clearance 0.0508)
			(thermal_gap 0.0508)
		)
		(pad "3" thru_hole circle
			(at 0 3.999992 180)
			(size 1.2192 1.2192)
			(drill 0.8128)
			(layers "*.Cu" "*.Mask")
			(remove_unused_layers no)
			(net "UART_CPU0_LVC3_UART0_TX")
			(clearance 0.0508)
			(thermal_gap 0.0508)
		)
		(pad "4" thru_hole circle
			(at 0 5.999988 180)
			(size 1.2192 1.2192)
			(drill 0.8128)
			(layers "*.Cu" "*.Mask")
			(remove_unused_layers no)
			(net "GND")
			(clearance 0.0508)
			(thermal_gap 0.0508)
		)
		(zone
			(layers "F.Cu" "B.Cu" "In1.Cu" "In2.Cu" "In3.Cu" "In4.Cu" "In5.Cu" "In6.Cu"
				"In7.Cu" "In8.Cu" "In9.Cu" "In10.Cu" "In11.Cu" "In12.Cu" "In13.Cu" "In14.Cu"
				"In15.Cu" "In16.Cu"
			)
			(hatch none 0.5)
			(connect_pads
				(clearance 0)
			)
			(min_thickness 0.25)
			(keepout
				(tracks not_allowed)
				(vias allowed)
				(pads allowed)
				(copperpour not_allowed)
				(footprints allowed)
			)
			(placement
				(enabled no)
				(sheetname "")
			)
			(fill
				(thermal_gap 0.5)
				(thermal_bridge_width 0.5)
				(island_removal_mode 0)
			)
			(polygon
				(pts
					(arc
						(start 370.536724 -20.418806)
						(mid 370.237657 -19.696793)
						(end 369.515644 -19.397726)
					)
					(arc
						(start 369.515644 -19.397726)
						(mid 368.507264 -20.406106)
						(end 369.515644 -21.414486)
					)
					(arc
						(start 369.541044 -21.414486)
						(mid 370.245096 -21.122858)
						(end 370.536724 -20.418806)
					)
				)
			)
		)
	)
	(footprint ""
		(layer "F.Cu")
		(at 208.661 -104.013 180)
		(property "Reference" "R8080"
			(at 0 0 180)
			(layer "F.SilkS")
			(hide yes)
			(effects
				(font
					(size 1.27 1.27)
				)
			)
		)
		(property "Value" ""
			(at 0 0 180)
			(layer "F.Fab")
			(effects
				(font
					(size 1.27 1.27)
				)
			)
		)
		(duplicate_pad_numbers_are_jumpers no)
		(fp_line
			(start 0.7874 0.4064)
			(end -0.7874 0.4064)
			(stroke
				(width 0.1524)
				(type default)
			)
			(layer "F.SilkS")
		)
		(fp_line
			(start 0.7874 -0.4064)
			(end 0.7874 0.4064)
			(stroke
				(width 0.1524)
				(type default)
			)
			(layer "F.SilkS")
		)
		(fp_line
			(start -0.7874 0.4064)
			(end -0.7874 -0.4064)
			(stroke
				(width 0.1524)
				(type default)
			)
			(layer "F.SilkS")
		)
		(fp_line
			(start -0.7874 -0.4064)
			(end 0.7874 -0.4064)
			(stroke
				(width 0.1524)
				(type default)
			)
			(layer "F.SilkS")
		)
		(fp_line
			(start 0.67945 0.3048)
			(end 0.120396 0.3048)
			(stroke
				(width 0.1)
				(type default)
			)
			(layer "F.Fab")
		)
		(fp_line
			(start 0.67945 -0.3048)
			(end 0.67945 0.3048)
			(stroke
				(width 0.1)
				(type default)
			)
			(layer "F.Fab")
		)
		(fp_line
			(start 0.12065 -0.2794)
			(end 0.12065 -0.3048)
			(stroke
				(width 0.1)
				(type default)
			)
			(layer "F.Fab")
		)
		(fp_line
			(start 0.12065 -0.3048)
			(end 0.67945 -0.3048)
			(stroke
				(width 0.1)
				(type default)
			)
			(layer "F.Fab")
		)
		(fp_line
			(start 0.120396 0.3048)
			(end 0.120396 0.2794)
			(stroke
				(width 0.1)
				(type default)
			)
			(layer "F.Fab")
		)
		(fp_line
			(start 0.120396 0.2794)
			(end -0.12065 0.2794)
			(stroke
				(width 0.1)
				(type default)
			)
			(layer "F.Fab")
		)
		(fp_line
			(start -0.12065 0.3048)
			(end -0.67945 0.3048)
			(stroke
				(width 0.1)
				(type default)
			)
			(layer "F.Fab")
		)
		(fp_line
			(start -0.12065 0.2794)
			(end -0.12065 0.3048)
			(stroke
				(width 0.1)
				(type default)
			)
			(layer "F.Fab")
		)
		(fp_line
			(start -0.12065 -0.2794)
			(end 0.12065 -0.2794)
			(stroke
				(width 0.1)
				(type default)
			)
			(layer "F.Fab")
		)
		(fp_line
			(start -0.12065 -0.305054)
			(end -0.12065 -0.2794)
			(stroke
				(width 0.1)
				(type default)
			)
			(layer "F.Fab")
		)
		(fp_line
			(start -0.67945 0.3048)
			(end -0.67945 -0.305054)
			(stroke
				(width 0.1)
				(type default)
			)
			(layer "F.Fab")
		)
		(fp_line
			(start -0.67945 -0.305054)
			(end -0.12065 -0.305054)
			(stroke
				(width 0.1)
				(type default)
			)
			(layer "F.Fab")
		)
		(pad "1" smd circle
			(at -0.40005 0 180)
			(size 0 0)
			(layers "F.Cu" "F.Mask" "F.Paste")
			(net "PWRGD_CHAF_CPU0")
		)
		(pad "2" smd circle
			(at 0.40005 0 180)
			(size 0 0)
			(layers "F.Cu" "F.Mask" "F.Paste")
			(net "PWRGD_CHAF_CPU0_R1")
		)
	)
)
